(kicad_pcb
	(version 20260206)
	(generator "pcbnew")
	(generator_version "10.0")
	(general
		(thickness 1.6)
		(legacy_teardrops no)
	)
	(paper "A4")
	(title_block
		(title "03242023_DA0F0TMBIJ0_F0T_Motherboard_J_brd_V01_OCP.brd")
		(comment 1 "Grand Teton / footprints 3624-3632 of 6105")
	)
	(layers
		(0 "F.Cu" signal "TOP")
		(4 "In1.Cu" signal "GND")
		(6 "In2.Cu" signal "IN1")
		(8 "In3.Cu" signal "GND1")
		(10 "In4.Cu" signal "IN2")
		(12 "In5.Cu" signal "GND2")
		(14 "In6.Cu" signal "IN3")
		(16 "In7.Cu" signal "GND3")
		(18 "In8.Cu" signal "VCC")
		(20 "In9.Cu" signal "VCC1")
		(22 "In10.Cu" signal "GND4")
		(24 "In11.Cu" signal "IN4")
		(26 "In12.Cu" signal "GND5")
		(28 "In13.Cu" signal "IN5")
		(30 "In14.Cu" signal "GND6")
		(32 "In15.Cu" signal "IN6")
		(34 "In16.Cu" signal "GND7")
		(2 "B.Cu" signal "BOTTOM")
		(9 "F.Adhes" user "F.Adhesive")
		(11 "B.Adhes" user "B.Adhesive")
		(13 "F.Paste" user "Package Geometry/Pastemask Top")
		(15 "B.Paste" user "Package Geometry/Pastemask Bottom")
		(5 "F.SilkS" user "Ref Des/Silkscreen Top")
		(7 "B.SilkS" user "Ref Des/Silkscreen Bottom")
		(1 "F.Mask" user "Board Geometry/Soldermask Top")
		(3 "B.Mask" user "Board Geometry/Soldermask Bottom")
		(17 "Dwgs.User" user "User.Drawings")
		(19 "Cmts.User" user "User.Comments")
		(21 "Eco1.User" user "User.Eco1")
		(23 "Eco2.User" user "User.Eco2")
		(25 "Edge.Cuts" user "Board Geometry/Outline")
		(27 "Margin" user)
		(31 "F.CrtYd" user "Package Geometry/Place Bound Top")
		(29 "B.CrtYd" user "Package Geometry/Place Bound Bottom")
		(35 "F.Fab" user "Ref Des/Assembly Top")
		(33 "B.Fab" user "Ref Des/Assembly Bottom")
	)
	(footprint ""
		(layer "F.Cu")
		(at 68.085716 -113.72469 180)
		(property "Reference" "R3711"
			(at 0 0 180)
			(layer "F.SilkS")
			(hide yes)
			(effects
				(font
					(size 1.27 1.27)
				)
			)
		)
		(property "Value" ""
			(at 0 0 180)
			(layer "F.Fab")
			(effects
				(font
					(size 1.27 1.27)
				)
			)
		)
		(duplicate_pad_numbers_are_jumpers no)
		(fp_line
			(start 0.7874 0.4064)
			(end -0.7874 0.4064)
			(stroke
				(width 0.1524)
				(type default)
			)
			(layer "F.SilkS")
		)
		(fp_line
			(start 0.7874 -0.4064)
			(end 0.7874 0.4064)
			(stroke
				(width 0.1524)
				(type default)
			)
			(layer "F.SilkS")
		)
		(fp_line
			(start -0.7874 0.4064)
			(end -0.7874 -0.4064)
			(stroke
				(width 0.1524)
				(type default)
			)
			(layer "F.SilkS")
		)
		(fp_line
			(start -0.7874 -0.4064)
			(end 0.7874 -0.4064)
			(stroke
				(width 0.1524)
				(type default)
			)
			(layer "F.SilkS")
		)
		(fp_line
			(start 0.67945 0.3048)
			(end 0.120396 0.3048)
			(stroke
				(width 0.1)
				(type default)
			)
			(layer "F.Fab")
		)
		(fp_line
			(start 0.67945 -0.3048)
			(end 0.67945 0.3048)
			(stroke
				(width 0.1)
				(type default)
			)
			(layer "F.Fab")
		)
		(fp_line
			(start 0.12065 -0.2794)
			(end 0.12065 -0.3048)
			(stroke
				(width 0.1)
				(type default)
			)
			(layer "F.Fab")
		)
		(fp_line
			(start 0.12065 -0.3048)
			(end 0.67945 -0.3048)
			(stroke
				(width 0.1)
				(type default)
			)
			(layer "F.Fab")
		)
		(fp_line
			(start 0.120396 0.3048)
			(end 0.120396 0.2794)
			(stroke
				(width 0.1)
				(type default)
			)
			(layer "F.Fab")
		)
		(fp_line
			(start 0.120396 0.2794)
			(end -0.12065 0.2794)
			(stroke
				(width 0.1)
				(type default)
			)
			(layer "F.Fab")
		)
		(fp_line
			(start -0.12065 0.3048)
			(end -0.67945 0.3048)
			(stroke
				(width 0.1)
				(type default)
			)
			(layer "F.Fab")
		)
		(fp_line
			(start -0.12065 0.2794)
			(end -0.12065 0.3048)
			(stroke
				(width 0.1)
				(type default)
			)
			(layer "F.Fab")
		)
		(fp_line
			(start -0.12065 -0.2794)
			(end 0.12065 -0.2794)
			(stroke
				(width 0.1)
				(type default)
			)
			(layer "F.Fab")
		)
		(fp_line
			(start -0.12065 -0.305054)
			(end -0.12065 -0.2794)
			(stroke
				(width 0.1)
				(type default)
			)
			(layer "F.Fab")
		)
		(fp_line
			(start -0.67945 0.3048)
			(end -0.67945 -0.305054)
			(stroke
				(width 0.1)
				(type default)
			)
			(layer "F.Fab")
		)
		(fp_line
			(start -0.67945 -0.305054)
			(end -0.12065 -0.305054)
			(stroke
				(width 0.1)
				(type default)
			)
			(layer "F.Fab")
		)
		(pad "1" smd circle
			(at -0.40005 0 180)
			(size 0 0)
			(layers "F.Cu" "F.Mask" "F.Paste")
			(net "SMB_VR_SENSOR_3V3AUX_SCL")
		)
		(pad "2" smd circle
			(at 0.40005 0 180)
			(size 0 0)
			(layers "F.Cu" "F.Mask" "F.Paste")
			(net "SMB_VR_SENSOR_3V3AUX_SCL_R")
		)
	)
	(footprint ""
		(layer "F.Cu")
		(at 150.761954 -402.371052 -90)
		(property "Reference" "C763"
			(at 0 0 270)
			(layer "F.SilkS")
			(hide yes)
			(effects
				(font
					(size 1.27 1.27)
				)
			)
		)
		(property "Value" ""
			(at 0 0 270)
			(layer "F.Fab")
			(effects
				(font
					(size 1.27 1.27)
				)
			)
		)
		(duplicate_pad_numbers_are_jumpers no)
		(fp_line
			(start -0.299974 0.150114)
			(end -0.299974 -0.150114)
			(stroke
				(width 0.1)
				(type default)
			)
			(layer "F.Fab")
		)
		(fp_line
			(start 0.299974 0.150114)
			(end -0.299974 0.150114)
			(stroke
				(width 0.1)
				(type default)
			)
			(layer "F.Fab")
		)
		(fp_line
			(start -0.299974 -0.150114)
			(end 0.299974 -0.150114)
			(stroke
				(width 0.1)
				(type default)
			)
			(layer "F.Fab")
		)
		(fp_line
			(start 0.299974 -0.150114)
			(end 0.299974 0.150114)
			(stroke
				(width 0.1)
				(type default)
			)
			(layer "F.Fab")
		)
		(pad "1" smd rect
			(at -0.2667 0 270)
			(size 0.3048 0.381)
			(layers "F.Cu" "F.Mask" "F.Paste")
			(net "P5E_CPU1_PE2_TX_C_DP<5>")
		)
		(pad "2" smd rect
			(at 0.2667 0 270)
			(size 0.3048 0.381)
			(layers "F.Cu" "F.Mask" "F.Paste")
			(net "P5E_CPU1_PE2_TX_DP<5>")
		)
	)
	(footprint ""
		(layer "F.Cu")
		(at 440.137804 -18.27022 180)
		(property "Reference" "C1213"
			(at 0 0 180)
			(layer "F.SilkS")
			(hide yes)
			(effects
				(font
					(size 1.27 1.27)
				)
			)
		)
		(property "Value" ""
			(at 0 0 180)
			(layer "F.Fab")
			(effects
				(font
					(size 1.27 1.27)
				)
			)
		)
		(duplicate_pad_numbers_are_jumpers no)
		(fp_line
			(start 1.524 0.762)
			(end -1.524 0.762)
			(stroke
				(width 0.1524)
				(type default)
			)
			(layer "F.SilkS")
		)
		(fp_line
			(start 1.524 -0.762)
			(end 1.524 0.762)
			(stroke
				(width 0.1524)
				(type default)
			)
			(layer "F.SilkS")
		)
		(fp_line
			(start -1.524 0.762)
			(end -1.524 -0.762)
			(stroke
				(width 0.1524)
				(type default)
			)
			(layer "F.SilkS")
		)
		(fp_line
			(start -1.524 -0.762)
			(end 1.524 -0.762)
			(stroke
				(width 0.1524)
				(type default)
			)
			(layer "F.SilkS")
		)
		(fp_line
			(start 1.1049 0.724916)
			(end 1.1049 -0.724916)
			(stroke
				(width 0.1)
				(type default)
			)
			(layer "F.Fab")
		)
		(fp_line
			(start 1.1049 -0.724916)
			(end -1.1049 -0.724916)
			(stroke
				(width 0.1)
				(type default)
			)
			(layer "F.Fab")
		)
		(fp_line
			(start -1.1049 0.724916)
			(end 1.1049 0.724916)
			(stroke
				(width 0.1)
				(type default)
			)
			(layer "F.Fab")
		)
		(fp_line
			(start -1.1049 -0.724916)
			(end -1.1049 0.724916)
			(stroke
				(width 0.1)
				(type default)
			)
			(layer "F.Fab")
		)
		(pad "1" smd rect
			(at -0.889 0)
			(size 1.016 1.27)
			(layers "F.Cu" "F.Mask" "F.Paste")
			(net "P12V_OCP_SFF")
		)
		(pad "2" smd rect
			(at 0.889 0)
			(size 1.016 1.27)
			(layers "F.Cu" "F.Mask" "F.Paste")
			(net "GND")
		)
	)
	(footprint ""
		(layer "F.Cu")
		(at 338.38007 -297.514772)
		(property "Reference" "H15"
			(at -1.83007 -5.064506 0)
			(unlocked yes)
			(layer "F.SilkS")
			(effects
				(font
					(size 0.7874 0.5842)
					(thickness 0.1524)
				)
				(justify left)
			)
		)
		(property "Value" ""
			(at 0 0 0)
			(layer "F.Fab")
			(effects
				(font
					(size 1.27 1.27)
				)
			)
		)
		(duplicate_pad_numbers_are_jumpers no)
		(fp_circle
			(center 0 0)
			(end 2.5273 0)
			(stroke
				(width 0.1524)
				(type default)
			)
			(fill no)
			(layer "F.SilkS")
		)
		(fp_circle
			(center 0 0)
			(end 2.5273 0)
			(stroke
				(width 0.1524)
				(type default)
			)
			(fill no)
			(layer "B.SilkS")
		)
		(fp_circle
			(center 0 0)
			(end 2.5273 0)
			(stroke
				(width 0.1)
				(type default)
			)
			(fill no)
			(layer "B.Fab")
		)
		(fp_circle
			(center 0 0)
			(end 2.5273 0)
			(stroke
				(width 0.1)
				(type default)
			)
			(fill no)
			(layer "F.Fab")
		)
		(pad "" np_thru_hole circle
			(at 0 0)
			(size 3.429 3.429)
			(drill 3.429)
			(layers "*.Cu" "*.Mask")
			(clearance 0.381)
			(thermal_gap 0.381)
		)
	)
	(footprint ""
		(layer "F.Cu")
		(at 312.42 -24.9936)
		(property "Reference" "R4788"
			(at 0 0 0)
			(layer "F.SilkS")
			(hide yes)
			(effects
				(font
					(size 1.27 1.27)
				)
			)
		)
		(property "Value" ""
			(at 0 0 0)
			(layer "F.Fab")
			(effects
				(font
					(size 1.27 1.27)
				)
			)
		)
		(duplicate_pad_numbers_are_jumpers no)
		(fp_line
			(start -0.7874 -0.4064)
			(end 0.7874 -0.4064)
			(stroke
				(width 0.1524)
				(type default)
			)
			(layer "F.SilkS")
		)
		(fp_line
			(start -0.7874 0.4064)
			(end -0.7874 -0.4064)
			(stroke
				(width 0.1524)
				(type default)
			)
			(layer "F.SilkS")
		)
		(fp_line
			(start 0.7874 -0.4064)
			(end 0.7874 0.4064)
			(stroke
				(width 0.1524)
				(type default)
			)
			(layer "F.SilkS")
		)
		(fp_line
			(start 0.7874 0.4064)
			(end -0.7874 0.4064)
			(stroke
				(width 0.1524)
				(type default)
			)
			(layer "F.SilkS")
		)
		(fp_line
			(start -0.67945 -0.305054)
			(end -0.12065 -0.305054)
			(stroke
				(width 0.1)
				(type default)
			)
			(layer "F.Fab")
		)
		(fp_line
			(start -0.67945 0.3048)
			(end -0.67945 -0.305054)
			(stroke
				(width 0.1)
				(type default)
			)
			(layer "F.Fab")
		)
		(fp_line
			(start -0.12065 -0.305054)
			(end -0.12065 -0.2794)
			(stroke
				(width 0.1)
				(type default)
			)
			(layer "F.Fab")
		)
		(fp_line
			(start -0.12065 -0.2794)
			(end 0.12065 -0.2794)
			(stroke
				(width 0.1)
				(type default)
			)
			(layer "F.Fab")
		)
		(fp_line
			(start -0.12065 0.2794)
			(end -0.12065 0.3048)
			(stroke
				(width 0.1)
				(type default)
			)
			(layer "F.Fab")
		)
		(fp_line
			(start -0.12065 0.3048)
			(end -0.67945 0.3048)
			(stroke
				(width 0.1)
				(type default)
			)
			(layer "F.Fab")
		)
		(fp_line
			(start 0.120396 0.2794)
			(end -0.12065 0.2794)
			(stroke
				(width 0.1)
				(type default)
			)
			(layer "F.Fab")
		)
		(fp_line
			(start 0.120396 0.3048)
			(end 0.120396 0.2794)
			(stroke
				(width 0.1)
				(type default)
			)
			(layer "F.Fab")
		)
		(fp_line
			(start 0.12065 -0.3048)
			(end 0.67945 -0.3048)
			(stroke
				(width 0.1)
				(type default)
			)
			(layer "F.Fab")
		)
		(fp_line
			(start 0.12065 -0.2794)
			(end 0.12065 -0.3048)
			(stroke
				(width 0.1)
				(type default)
			)
			(layer "F.Fab")
		)
		(fp_line
			(start 0.67945 -0.3048)
			(end 0.67945 0.3048)
			(stroke
				(width 0.1)
				(type default)
			)
			(layer "F.Fab")
		)
		(fp_line
			(start 0.67945 0.3048)
			(end 0.120396 0.3048)
			(stroke
				(width 0.1)
				(type default)
			)
			(layer "F.Fab")
		)
		(pad "1" smd circle
			(at -0.40005 0)
			(size 0 0)
			(layers "F.Cu" "F.Mask" "F.Paste")
			(net "PWRGD_DSW_PWROK_R5")
		)
		(pad "2" smd circle
			(at 0.40005 0)
			(size 0 0)
			(layers "F.Cu" "F.Mask" "F.Paste")
			(net "PWRGD_DSW_PWROK")
		)
	)
	(footprint ""
		(layer "F.Cu")
		(at 23.767034 -385.778248 -90)
		(property "Reference" "C1868"
			(at 0 0 270)
			(layer "F.SilkS")
			(hide yes)
			(effects
				(font
					(size 1.27 1.27)
				)
			)
		)
		(property "Value" ""
			(at 0 0 270)
			(layer "F.Fab")
			(effects
				(font
					(size 1.27 1.27)
				)
			)
		)
		(duplicate_pad_numbers_are_jumpers no)
		(fp_line
			(start -0.002032 0.4064)
			(end -0.7874 0.4064)
			(stroke
				(width 0.1524)
				(type default)
			)
			(layer "F.SilkS")
		)
		(fp_line
			(start -0.7874 -0.4064)
			(end 0.7874 -0.4064)
			(stroke
				(width 0.1524)
				(type default)
			)
			(layer "F.SilkS")
		)
		(fp_line
			(start 0.7874 -0.4064)
			(end 0.7874 0.4064)
			(stroke
				(width 0.1524)
				(type default)
			)
			(layer "F.SilkS")
		)
		(fp_line
			(start -0.6858 0.3048)
			(end -0.6858 -0.3048)
			(stroke
				(width 0.1)
				(type default)
			)
			(layer "F.Fab")
		)
		(fp_line
			(start -0.1016 0.3048)
			(end -0.6858 0.3048)
			(stroke
				(width 0.1)
				(type default)
			)
			(layer "F.Fab")
		)
		(fp_line
			(start 0.1016 0.3048)
			(end 0.1016 0.2794)
			(stroke
				(width 0.1)
				(type default)
			)
			(layer "F.Fab")
		)
		(fp_line
			(start 0.6858 0.3048)
			(end 0.1016 0.3048)
			(stroke
				(width 0.1)
				(type default)
			)
			(layer "F.Fab")
		)
		(fp_line
			(start -0.1016 0.2794)
			(end -0.1016 0.3048)
			(stroke
				(width 0.1)
				(type default)
			)
			(layer "F.Fab")
		)
		(fp_line
			(start 0.1016 0.2794)
			(end -0.1016 0.2794)
			(stroke
				(width 0.1)
				(type default)
			)
			(layer "F.Fab")
		)
		(fp_line
			(start -0.1016 -0.2794)
			(end 0.1016 -0.2794)
			(stroke
				(width 0.1)
				(type default)
			)
			(layer "F.Fab")
		)
		(fp_line
			(start 0.1016 -0.2794)
			(end 0.1016 -0.3048)
			(stroke
				(width 0.1)
				(type default)
			)
			(layer "F.Fab")
		)
		(fp_line
			(start -0.6858 -0.3048)
			(end -0.1016 -0.3048)
			(stroke
				(width 0.1)
				(type default)
			)
			(layer "F.Fab")
		)
		(fp_line
			(start -0.1016 -0.3048)
			(end -0.1016 -0.2794)
			(stroke
				(width 0.1)
				(type default)
			)
			(layer "F.Fab")
		)
		(fp_line
			(start 0.1016 -0.3048)
			(end 0.6858 -0.3048)
			(stroke
				(width 0.1)
				(type default)
			)
			(layer "F.Fab")
		)
		(fp_line
			(start 0.6858 -0.3048)
			(end 0.6858 0.3048)
			(stroke
				(width 0.1)
				(type default)
			)
			(layer "F.Fab")
		)
		(pad "1" smd rect
			(at -0.40005 0 90)
			(size 0.4572 0.508)
			(layers "F.Cu" "F.Mask" "F.Paste")
			(net "P2E_MB_BMC_RX_BUF_C_DP<0>")
		)
		(pad "2" smd rect
			(at 0.40005 0 90)
			(size 0.4572 0.508)
			(layers "F.Cu" "F.Mask" "F.Paste")
			(net "P2E_MB_BMC_RX_BUF_DP<0>")
		)
	)
	(footprint ""
		(layer "F.Cu")
		(at 98.525838 -315.66739 90)
		(property "Reference" "PC580"
			(at 0 0 90)
			(layer "F.SilkS")
			(hide yes)
			(effects
				(font
					(size 1.27 1.27)
				)
			)
		)
		(property "Value" ""
			(at 0 0 90)
			(layer "F.Fab")
			(effects
				(font
					(size 1.27 1.27)
				)
			)
		)
		(duplicate_pad_numbers_are_jumpers no)
		(fp_line
			(start 2.750058 0.999998)
			(end -2.750058 0.999998)
			(stroke
				(width 0.1524)
				(type default)
			)
			(layer "F.SilkS")
		)
		(fp_circle
			(center 0 0.999998)
			(end 0 3.750056)
			(stroke
				(width 0.1524)
				(type default)
			)
			(fill no)
			(layer "F.SilkS")
		)
		(fp_poly
			(pts
				(arc
					(start 2.750058 0.999998)
					(mid 0 3.750056)
					(end -2.750058 0.999998)
				)
			)
			(stroke
				(width 0)
				(type default)
			)
			(fill yes)
			(layer "F.SilkS")
		)
		(fp_circle
			(center 0 0.999998)
			(end 0 3.750056)
			(stroke
				(width 0.1)
				(type default)
			)
			(fill no)
			(layer "F.Fab")
		)
		(pad "1" thru_hole rect
			(at 0 0 90)
			(size 1.5748 1.5748)
			(drill 1.0668)
			(layers "*.Cu" "*.Mask")
			(remove_unused_layers no)
			(net "PVCCIN_CPU1")
			(clearance 0)
			(padstack
				(mode front_inner_back)
				(layer "Inner"
					(shape circle)
					(size 1.5748 1.5748)
					(clearance 0)
				)
				(layer "B.Cu"
					(shape rect)
					(size 1.5748 1.5748)
					(clearance 0)
				)
			)
		)
		(pad "2" thru_hole circle
			(at 0 1.999996 90)
			(size 1.5748 1.5748)
			(drill 1.0668)
			(layers "*.Cu" "*.Mask")
			(remove_unused_layers no)
			(net "GND")
			(clearance 0)
		)
	)
	(footprint ""
		(layer "F.Cu")
		(at 77.920088 -251.76988)
		(property "Reference" "H24"
			(at -4.47802 -1.615948 0)
			(unlocked yes)
			(layer "F.SilkS")
			(effects
				(font
					(size 0.7874 0.5842)
					(thickness 0.1524)
				)
				(justify left)
			)
		)
		(property "Value" ""
			(at 0 0 0)
			(layer "F.Fab")
			(effects
				(font
					(size 1.27 1.27)
				)
			)
		)
		(duplicate_pad_numbers_are_jumpers no)
		(fp_circle
			(center 0 0)
			(end 2.5273 0)
			(stroke
				(width 0.1524)
				(type default)
			)
			(fill no)
			(layer "F.SilkS")
		)
		(fp_circle
			(center 0 0)
			(end 2.5273 0)
			(stroke
				(width 0.1524)
				(type default)
			)
			(fill no)
			(layer "B.SilkS")
		)
		(fp_circle
			(center 0 0)
			(end 2.5273 0)
			(stroke
				(width 0.1)
				(type default)
			)
			(fill no)
			(layer "B.Fab")
		)
		(fp_circle
			(center 0 0)
			(end 2.5273 0)
			(stroke
				(width 0.1)
				(type default)
			)
			(fill no)
			(layer "F.Fab")
		)
		(pad "" np_thru_hole circle
			(at 0 0)
			(size 3.429 3.429)
			(drill 3.429)
			(layers "*.Cu" "*.Mask")
			(clearance 0.381)
			(thermal_gap 0.381)
		)
	)
	(footprint ""
		(layer "F.Cu")
		(at 106.7308 -410.6164 180)
		(property "Reference" "R4725"
			(at 0 0 180)
			(layer "F.SilkS")
			(hide yes)
			(effects
				(font
					(size 1.27 1.27)
				)
			)
		)
		(property "Value" ""
			(at 0 0 180)
			(layer "F.Fab")
			(effects
				(font
					(size 1.27 1.27)
				)
			)
		)
		(duplicate_pad_numbers_are_jumpers no)
		(fp_line
			(start 0.7874 0.4064)
			(end -0.7874 0.4064)
			(stroke
				(width 0.1524)
				(type default)
			)
			(layer "F.SilkS")
		)
		(fp_line
			(start 0.7874 -0.4064)
			(end 0.7874 0.4064)
			(stroke
				(width 0.1524)
				(type default)
			)
			(layer "F.SilkS")
		)
		(fp_line
			(start -0.7874 0.4064)
			(end -0.7874 -0.4064)
			(stroke
				(width 0.1524)
				(type default)
			)
			(layer "F.SilkS")
		)
		(fp_line
			(start -0.7874 -0.4064)
			(end 0.7874 -0.4064)
			(stroke
				(width 0.1524)
				(type default)
			)
			(layer "F.SilkS")
		)
		(fp_line
			(start 0.67945 0.3048)
			(end 0.120396 0.3048)
			(stroke
				(width 0.1)
				(type default)
			)
			(layer "F.Fab")
		)
		(fp_line
			(start 0.67945 -0.3048)
			(end 0.67945 0.3048)
			(stroke
				(width 0.1)
				(type default)
			)
			(layer "F.Fab")
		)
		(fp_line
			(start 0.12065 -0.2794)
			(end 0.12065 -0.3048)
			(stroke
				(width 0.1)
				(type default)
			)
			(layer "F.Fab")
		)
		(fp_line
			(start 0.12065 -0.3048)
			(end 0.67945 -0.3048)
			(stroke
				(width 0.1)
				(type default)
			)
			(layer "F.Fab")
		)
		(fp_line
			(start 0.120396 0.3048)
			(end 0.120396 0.2794)
			(stroke
				(width 0.1)
				(type default)
			)
			(layer "F.Fab")
		)
		(fp_line
			(start 0.120396 0.2794)
			(end -0.12065 0.2794)
			(stroke
				(width 0.1)
				(type default)
			)
			(layer "F.Fab")
		)
		(fp_line
			(start -0.12065 0.3048)
			(end -0.67945 0.3048)
			(stroke
				(width 0.1)
				(type default)
			)
			(layer "F.Fab")
		)
		(fp_line
			(start -0.12065 0.2794)
			(end -0.12065 0.3048)
			(stroke
				(width 0.1)
				(type default)
			)
			(layer "F.Fab")
		)
		(fp_line
			(start -0.12065 -0.2794)
			(end 0.12065 -0.2794)
			(stroke
				(width 0.1)
				(type default)
			)
			(layer "F.Fab")
		)
		(fp_line
			(start -0.12065 -0.305054)
			(end -0.12065 -0.2794)
			(stroke
				(width 0.1)
				(type default)
			)
			(layer "F.Fab")
		)
		(fp_line
			(start -0.67945 0.3048)
			(end -0.67945 -0.305054)
			(stroke
				(width 0.1)
				(type default)
			)
			(layer "F.Fab")
		)
		(fp_line
			(start -0.67945 -0.305054)
			(end -0.12065 -0.305054)
			(stroke
				(width 0.1)
				(type default)
			)
			(layer "F.Fab")
		)
		(pad "1" smd circle
			(at -0.40005 0 180)
			(size 0 0)
			(layers "F.Cu" "F.Mask" "F.Paste")
			(net "P3V3_AUX")
		)
		(pad "2" smd circle
			(at 0.40005 0 180)
			(size 0 0)
			(layers "F.Cu" "F.Mask" "F.Paste")
			(net "PRSNT_SWB")
		)
	)
)
